(kicad_pcb
	(version 20260206)
	(generator "pcbnew")
	(generator_version "10.0")
	(general
		(thickness 1.6)
		(legacy_teardrops no)
	)
	(paper "A4")
	(title_block
		(title "Bryce Canyon_SCC_16316-1_OCP.brd")
		(comment 1 "Bryce Canyon / footprints 272-276 of 1561")
	)
	(layers
		(0 "F.Cu" signal "TOP")
		(4 "In1.Cu" signal "L2GND")
		(6 "In2.Cu" signal "L3")
		(8 "In3.Cu" signal "L4VCC")
		(10 "In4.Cu" signal "L5VCC")
		(12 "In5.Cu" signal "L6")
		(14 "In6.Cu" signal "L7GND")
		(2 "B.Cu" signal "BOTTOM")
		(9 "F.Adhes" user "F.Adhesive")
		(11 "B.Adhes" user "B.Adhesive")
		(13 "F.Paste" user "Package Geometry/Pastemask Top")
		(15 "B.Paste" user "Package Geometry/Pastemask Bottom")
		(5 "F.SilkS" user "Ref Des/Silkscreen Top")
		(7 "B.SilkS" user "Ref Des/Silkscreen Bottom")
		(1 "F.Mask" user "Board Geometry/Soldermask Top")
		(3 "B.Mask" user "Board Geometry/Soldermask Bottom")
		(17 "Dwgs.User" user "User.Drawings")
		(19 "Cmts.User" user "User.Comments")
		(21 "Eco1.User" user "User.Eco1")
		(23 "Eco2.User" user "User.Eco2")
		(25 "Edge.Cuts" user "Board Geometry/Outline")
		(27 "Margin" user)
		(31 "F.CrtYd" user "Package Geometry/Place Bound Top")
		(29 "B.CrtYd" user "Package Geometry/Place Bound Bottom")
		(35 "F.Fab" user "Ref Des/Assembly Top")
		(33 "B.Fab" user "Ref Des/Assembly Bottom")
	)
	(footprint ""
		(layer "F.Cu")
		(at 48.680878 -38.911784 90)
		(property "Reference" "R482"
			(at 0 0 90)
			(layer "F.SilkS")
			(hide yes)
			(effects
				(font
					(size 1.27 1.27)
				)
			)
		)
		(property "Value" "0R3J-0-U-GP"
			(at -0.0254 -2.5146 90)
			(unlocked yes)
			(layer "F.Fab")
			(hide yes)
			(effects
				(font
					(size 1.016 1.016)
					(thickness 0.1524)
				)
			)
		)
		(property "Device Type" "R603H22"
			(at -0.0254 -4.0386 90)
			(unlocked yes)
			(layer "F.Fab")
			(hide yes)
			(effects
				(font
					(size 1.016 1.016)
					(thickness 0.1524)
				)
			)
		)
		(duplicate_pad_numbers_are_jumpers no)
		(fp_line
			(start 0.2032 0)
			(end 0.4826 0)
			(stroke
				(width 0.2032)
				(type default)
			)
			(layer "F.SilkS")
		)
		(fp_line
			(start -0.4826 0)
			(end -0.2032 0)
			(stroke
				(width 0.2032)
				(type default)
			)
			(layer "F.SilkS")
		)
		(fp_rect
			(start -0.5842 1.3335)
			(end 0.5842 -1.3335)
			(stroke
				(width 0)
				(type default)
			)
			(fill no)
			(layer "F.CrtYd")
		)
		(fp_rect
			(start -0.5842 1.3335)
			(end 0.5842 -1.3335)
			(stroke
				(width 0)
				(type default)
			)
			(fill no)
			(layer "F.Fab")
		)
		(pad "1" smd custom
			(at 0 -0.762 90)
			(size 0.2159 0.2159)
			(layers "F.Cu" "F.Mask" "F.Paste")
			(net "P0V9_V5")
			(options
				(clearance outline)
				(anchor circle)
			)
			(primitives
				(gr_poly
					(pts
						(arc
							(start -0.3302 -0.4318)
							(mid -0.402042 -0.402042)
							(end -0.4318 -0.3302)
						)
						(arc
							(start -0.4318 0.3302)
							(mid -0.402042 0.402042)
							(end -0.3302 0.4318)
						)
						(arc
							(start 0.3302 0.4318)
							(mid 0.402042 0.402042)
							(end 0.4318 0.3302)
						)
						(arc
							(start 0.4318 -0.3302)
							(mid 0.402042 -0.402042)
							(end 0.3302 -0.4318)
						)
					)
					(width 0)
					(fill yes)
				)
			)
		)
		(pad "2" smd custom
			(at 0 0.762 90)
			(size 0.2159 0.2159)
			(layers "F.Cu" "F.Mask" "F.Paste")
			(net "P5V")
			(options
				(clearance outline)
				(anchor circle)
			)
			(primitives
				(gr_poly
					(pts
						(arc
							(start -0.3302 -0.4318)
							(mid -0.402042 -0.402042)
							(end -0.4318 -0.3302)
						)
						(arc
							(start -0.4318 0.3302)
							(mid -0.402042 0.402042)
							(end -0.3302 0.4318)
						)
						(arc
							(start 0.3302 0.4318)
							(mid 0.402042 0.402042)
							(end 0.4318 0.3302)
						)
						(arc
							(start 0.4318 -0.3302)
							(mid 0.402042 -0.402042)
							(end 0.3302 -0.4318)
						)
					)
					(width 0)
					(fill yes)
				)
			)
		)
	)
	(footprint ""
		(layer "F.Cu")
		(at 182.7022 -55.6768 180)
		(property "Reference" "R221"
			(at 0 0 180)
			(layer "F.SilkS")
			(hide yes)
			(effects
				(font
					(size 1.27 1.27)
				)
			)
		)
		(property "Value" "10KR2F-2-GP"
			(at 0.064008 -3.993896 180)
			(unlocked yes)
			(layer "F.Fab")
			(hide yes)
			(effects
				(font
					(size 1.016 1.016)
					(thickness 0.1524)
				)
			)
		)
		(property "Device Type" "R402H16"
			(at 0.064008 -5.517896 180)
			(unlocked yes)
			(layer "F.Fab")
			(hide yes)
			(effects
				(font
					(size 1.016 1.016)
					(thickness 0.1524)
				)
			)
		)
		(duplicate_pad_numbers_are_jumpers no)
		(fp_line
			(start 0.508 -0.9398)
			(end -0.508 -0.9398)
			(stroke
				(width 0.1524)
				(type default)
			)
			(layer "F.SilkS")
		)
		(fp_line
			(start -0.508 -0.9398)
			(end -0.508 0.9398)
			(stroke
				(width 0.1524)
				(type default)
			)
			(layer "F.SilkS")
		)
		(fp_rect
			(start -0.508 0.9398)
			(end 0.508 -0.9398)
			(stroke
				(width 0)
				(type default)
			)
			(fill no)
			(layer "F.CrtYd")
		)
		(fp_rect
			(start -0.508 0.9398)
			(end 0.508 -0.9398)
			(stroke
				(width 0)
				(type default)
			)
			(fill no)
			(layer "F.Fab")
		)
		(pad "1" smd custom
			(at 0 -0.4445 180)
			(size 0.1397 0.1397)
			(layers "F.Cu" "F.Mask" "F.Paste")
			(net "XM_ADDR_0")
			(options
				(clearance outline)
				(anchor circle)
			)
			(primitives
				(gr_poly
					(pts
						(arc
							(start -0.1778 -0.2794)
							(mid -0.249642 -0.249642)
							(end -0.2794 -0.1778)
						)
						(arc
							(start -0.2794 0.1778)
							(mid -0.249642 0.249642)
							(end -0.1778 0.2794)
						)
						(arc
							(start 0.1778 0.2794)
							(mid 0.249642 0.249642)
							(end 0.2794 0.1778)
						)
						(arc
							(start 0.2794 -0.1778)
							(mid 0.249642 -0.249642)
							(end 0.1778 -0.2794)
						)
					)
					(width 0)
					(fill yes)
				)
			)
		)
		(pad "2" smd custom
			(at 0 0.4445 180)
			(size 0.1397 0.1397)
			(layers "F.Cu" "F.Mask" "F.Paste")
			(net "GND")
			(options
				(clearance outline)
				(anchor circle)
			)
			(primitives
				(gr_poly
					(pts
						(arc
							(start -0.1778 -0.2794)
							(mid -0.249642 -0.249642)
							(end -0.2794 -0.1778)
						)
						(arc
							(start -0.2794 0.1778)
							(mid -0.249642 0.249642)
							(end -0.1778 0.2794)
						)
						(arc
							(start 0.1778 0.2794)
							(mid 0.249642 0.249642)
							(end 0.2794 0.1778)
						)
						(arc
							(start 0.2794 -0.1778)
							(mid 0.249642 -0.249642)
							(end 0.1778 -0.2794)
						)
					)
					(width 0)
					(fill yes)
				)
			)
		)
	)
	(footprint ""
		(layer "F.Cu")
		(at 155.74518 -76.019406 -90)
		(property "Reference" "U26"
			(at 0 0 270)
			(layer "F.SilkS")
			(hide yes)
			(effects
				(font
					(size 1.27 1.27)
				)
			)
		)
		(property "Value" "ADS1015IDGSR-GP"
			(at 0 -11.1252 270)
			(unlocked yes)
			(layer "F.Fab")
			(hide yes)
			(effects
				(font
					(size 1.016 1.016)
					(thickness 0.1524)
				)
			)
		)
		(property "Device Type" "MSOP10H44"
			(at 0 -12.6492 270)
			(unlocked yes)
			(layer "F.Fab")
			(hide yes)
			(effects
				(font
					(size 1.016 1.016)
					(thickness 0.1524)
				)
			)
		)
		(duplicate_pad_numbers_are_jumpers no)
		(fp_line
			(start -2.0066 1.016)
			(end -2.0066 -1.016)
			(stroke
				(width 0.1524)
				(type default)
			)
			(layer "F.SilkS")
		)
		(fp_line
			(start -1.8288 1.016)
			(end -1.8288 3.048)
			(stroke
				(width 0.508)
				(type default)
			)
			(layer "F.SilkS")
		)
		(fp_line
			(start 1.143 1.016)
			(end -2.0066 1.016)
			(stroke
				(width 0.1524)
				(type default)
			)
			(layer "F.SilkS")
		)
		(fp_line
			(start -1.5748 0)
			(end -1.9558 0.381)
			(stroke
				(width 0.1524)
				(type default)
			)
			(layer "F.SilkS")
		)
		(fp_line
			(start -1.5748 0)
			(end -1.9558 -0.381)
			(stroke
				(width 0.1524)
				(type default)
			)
			(layer "F.SilkS")
		)
		(fp_line
			(start -2.0066 -1.016)
			(end 1.143 -1.016)
			(stroke
				(width 0.1524)
				(type default)
			)
			(layer "F.SilkS")
		)
		(fp_line
			(start 1.143 -1.016)
			(end 1.143 1.016)
			(stroke
				(width 0.1524)
				(type default)
			)
			(layer "F.SilkS")
		)
		(fp_poly
			(pts
				(xy -2.0828 3.3401) (xy 2.0828 3.3401) (xy 2.0828 -3.3401) (xy -2.0828 -3.3401)
			)
			(stroke
				(width 0)
				(type default)
			)
			(fill no)
			(layer "F.CrtYd")
		)
		(fp_poly
			(pts
				(xy -2.0828 3.3401) (xy 2.0828 3.3401) (xy 2.0828 -3.3401) (xy -2.0828 -3.3401)
			)
			(stroke
				(width 0)
				(type default)
			)
			(fill no)
			(layer "F.Fab")
		)
		(pad "1" smd rect
			(at -0.99949 2.0701 270)
			(size 0.3048 1.524)
			(layers "F.Cu" "F.Mask" "F.Paste")
			(net "VOL_SEN2_ADDR")
		)
		(pad "2" smd rect
			(at -0.50038 2.0701 270)
			(size 0.3048 1.524)
			(layers "F.Cu" "F.Mask" "F.Paste")
			(net "VOL_SEN2_ALERT")
		)
		(pad "3" smd rect
			(at 0 2.0701 270)
			(size 0.3048 1.524)
			(layers "F.Cu" "F.Mask" "F.Paste")
			(net "GND")
		)
		(pad "4" smd rect
			(at 0.50038 2.0701 270)
			(size 0.3048 1.524)
			(layers "F.Cu" "F.Mask" "F.Paste")
			(net "Net_68")
		)
		(pad "5" smd rect
			(at 0.99949 2.0701 270)
			(size 0.3048 1.524)
			(layers "F.Cu" "F.Mask" "F.Paste")
			(net "P1V8_C_SENSE")
		)
		(pad "6" smd rect
			(at 0.99949 -2.0701 270)
			(size 0.3048 1.524)
			(layers "F.Cu" "F.Mask" "F.Paste")
			(net "P1V5_C_SENSE")
		)
		(pad "7" smd rect
			(at 0.50038 -2.0701 270)
			(size 0.3048 1.524)
			(layers "F.Cu" "F.Mask" "F.Paste")
			(net "P0V975_SENSE")
		)
		(pad "8" smd rect
			(at 0 -2.0701 270)
			(size 0.3048 1.524)
			(layers "F.Cu" "F.Mask" "F.Paste")
			(net "P3V3")
		)
		(pad "9" smd rect
			(at -0.50038 -2.0701 270)
			(size 0.3048 1.524)
			(layers "F.Cu" "F.Mask" "F.Paste")
			(net "VOL_SEN2_SDA")
		)
		(pad "10" smd rect
			(at -0.99949 -2.0701 270)
			(size 0.3048 1.524)
			(layers "F.Cu" "F.Mask" "F.Paste")
			(net "VOL_SEN2_SCL")
		)
	)
	(footprint ""
		(layer "F.Cu")
		(at 125.526546 -44.74718 180)
		(property "Reference" "C47"
			(at 0 0 180)
			(layer "F.SilkS")
			(hide yes)
			(effects
				(font
					(size 1.27 1.27)
				)
			)
		)
		(property "Value" "SCD01U16V1KX-GP"
			(at -2.8321 -1.7399 180)
			(unlocked yes)
			(layer "F.Fab")
			(hide yes)
			(effects
				(font
					(size 1.016 1.016)
					(thickness 0.1524)
				)
			)
		)
		(property "Device Type" "C0201H13"
			(at -2.8321 -3.2639 180)
			(unlocked yes)
			(layer "F.Fab")
			(hide yes)
			(effects
				(font
					(size 1.016 1.016)
					(thickness 0.1524)
				)
			)
		)
		(duplicate_pad_numbers_are_jumpers no)
		(fp_rect
			(start -0.2794 0.6477)
			(end 0.2794 -0.6477)
			(stroke
				(width 0)
				(type default)
			)
			(fill no)
			(layer "F.CrtYd")
		)
		(fp_rect
			(start -0.2794 0.6477)
			(end 0.2794 -0.6477)
			(stroke
				(width 0)
				(type default)
			)
			(fill no)
			(layer "F.Fab")
		)
		(pad "1" smd custom
			(at 0 -0.2794 180)
			(size 0.0762 0.0762)
			(layers "F.Cu" "F.Mask" "F.Paste")
			(net "PHY_IOC_TO_SCC_40_DP")
			(options
				(clearance outline)
				(anchor circle)
			)
			(primitives
				(gr_poly
					(pts
						(arc
							(start 0.1524 -0.127)
							(mid 0.137521 -0.162921)
							(end 0.1016 -0.1778)
						)
						(arc
							(start -0.1016 -0.1778)
							(mid -0.137521 -0.162921)
							(end -0.1524 -0.127)
						)
						(arc
							(start -0.1524 0.127)
							(mid -0.137521 0.162921)
							(end -0.1016 0.1778)
						)
						(arc
							(start 0.1016 0.1778)
							(mid 0.137521 0.162921)
							(end 0.1524 0.127)
						)
					)
					(width 0)
					(fill yes)
				)
			)
		)
		(pad "2" smd custom
			(at 0 0.2794 180)
			(size 0.0762 0.0762)
			(layers "F.Cu" "F.Mask" "F.Paste")
			(net "PHY_IOC_TO_SCC_C_40_DP")
			(options
				(clearance outline)
				(anchor circle)
			)
			(primitives
				(gr_poly
					(pts
						(arc
							(start 0.1524 -0.127)
							(mid 0.137521 -0.162921)
							(end 0.1016 -0.1778)
						)
						(arc
							(start -0.1016 -0.1778)
							(mid -0.137521 -0.162921)
							(end -0.1524 -0.127)
						)
						(arc
							(start -0.1524 0.127)
							(mid -0.137521 0.162921)
							(end -0.1016 0.1778)
						)
						(arc
							(start 0.1016 0.1778)
							(mid 0.137521 0.162921)
							(end 0.1524 0.127)
						)
					)
					(width 0)
					(fill yes)
				)
			)
		)
	)
	(footprint ""
		(layer "F.Cu")
		(at 10.9728 -67.5894 -90)
		(property "Reference" "R609"
			(at 0 0 270)
			(layer "F.SilkS")
			(hide yes)
			(effects
				(font
					(size 1.27 1.27)
				)
			)
		)
		(property "Value" "75KR2J-GP"
			(at 0.064008 -3.993896 270)
			(unlocked yes)
			(layer "F.Fab")
			(hide yes)
			(effects
				(font
					(size 1.016 1.016)
					(thickness 0.1524)
				)
			)
		)
		(property "Device Type" "R402H16"
			(at 0.064008 -5.517896 270)
			(unlocked yes)
			(layer "F.Fab")
			(hide yes)
			(effects
				(font
					(size 1.016 1.016)
					(thickness 0.1524)
				)
			)
		)
		(duplicate_pad_numbers_are_jumpers no)
		(fp_line
			(start -0.508 -0.9398)
			(end -0.508 0.9398)
			(stroke
				(width 0.1524)
				(type default)
			)
			(layer "F.SilkS")
		)
		(fp_line
			(start 0.508 -0.9398)
			(end -0.508 -0.9398)
			(stroke
				(width 0.1524)
				(type default)
			)
			(layer "F.SilkS")
		)
		(fp_rect
			(start -0.508 0.9398)
			(end 0.508 -0.9398)
			(stroke
				(width 0)
				(type default)
			)
			(fill no)
			(layer "F.CrtYd")
		)
		(fp_rect
			(start -0.508 0.9398)
			(end 0.508 -0.9398)
			(stroke
				(width 0)
				(type default)
			)
			(fill no)
			(layer "F.Fab")
		)
		(pad "1" smd custom
			(at 0 -0.4445 270)
			(size 0.1397 0.1397)
			(layers "F.Cu" "F.Mask" "F.Paste")
			(net "P12V_MAIN")
			(options
				(clearance outline)
				(anchor circle)
			)
			(primitives
				(gr_poly
					(pts
						(arc
							(start -0.1778 -0.2794)
							(mid -0.249642 -0.249642)
							(end -0.2794 -0.1778)
						)
						(arc
							(start -0.2794 0.1778)
							(mid -0.249642 0.249642)
							(end -0.1778 0.2794)
						)
						(arc
							(start 0.1778 0.2794)
							(mid 0.249642 0.249642)
							(end 0.2794 0.1778)
						)
						(arc
							(start 0.2794 -0.1778)
							(mid 0.249642 -0.249642)
							(end 0.1778 -0.2794)
						)
					)
					(width 0)
					(fill yes)
				)
			)
		)
		(pad "2" smd custom
			(at 0 0.4445 270)
			(size 0.1397 0.1397)
			(layers "F.Cu" "F.Mask" "F.Paste")
			(net "MB0_HS_ENABLE_R")
			(options
				(clearance outline)
				(anchor circle)
			)
			(primitives
				(gr_poly
					(pts
						(arc
							(start -0.1778 -0.2794)
							(mid -0.249642 -0.249642)
							(end -0.2794 -0.1778)
						)
						(arc
							(start -0.2794 0.1778)
							(mid -0.249642 0.249642)
							(end -0.1778 0.2794)
						)
						(arc
							(start 0.1778 0.2794)
							(mid 0.249642 0.249642)
							(end 0.2794 0.1778)
						)
						(arc
							(start 0.2794 -0.1778)
							(mid 0.249642 -0.249642)
							(end 0.1778 -0.2794)
						)
					)
					(width 0)
					(fill yes)
				)
			)
		)
	)
)
